# BASEBOARD_FAB2 (Tioga Pass) — schematic netlist excerpt (pin names and nets, part order shuffled) for the footprints in the layout excerpt that follows; sources: Cadence DE-HDL packaged netlist, KiCad conversion of Wiwynn_Tioga_Pass_MB.brd

R25W18  120R2F-GP  1%  pkg RCL_GP  page 151 : \1\ = GND ; \2\ = BMC_M_A6
R1C12  RES  100.0 1% CHIP  pkg 0402  page 210 : A = VSENSE_PVSA_CPU1_P ; B = PVSA_CPU1
R6N3  RES  0.0 5% CHIP  pkg 0402  page 205 : A = VR_PVSA_CPU0_VCIN ; B = P5V_STBY

(kicad_pcb
	(version 20260206)
	(generator "pcbnew")
	(generator_version "10.0")
	(general
		(thickness 1.6)
		(legacy_teardrops no)
	)
	(paper "A4")
	(title_block
		(title "Wiwynn_Tioga_Pass_MB.brd")
		(comment 1 "Tioga Pass / footprints 3594-3596 of 4770")
	)
	(layers
		(0 "F.Cu" signal "TOP")
		(4 "In1.Cu" signal "L2GND")
		(6 "In2.Cu" signal "L3")
		(8 "In3.Cu" signal "L4GND")
		(10 "In4.Cu" signal "L5")
		(12 "In5.Cu" signal "L6GND")
		(14 "In6.Cu" signal "L7VCC")
		(16 "In7.Cu" signal "L8VCC")
		(18 "In8.Cu" signal "L9GND")
		(20 "In9.Cu" signal "L10")
		(22 "In10.Cu" signal "L11GND")
		(24 "In11.Cu" signal "L12")
		(26 "In12.Cu" signal "L13GND")
		(2 "B.Cu" signal "BOTTOM")
		(9 "F.Adhes" user "F.Adhesive")
		(11 "B.Adhes" user "B.Adhesive")
		(13 "F.Paste" user "Package Geometry/Pastemask Top")
		(15 "B.Paste" user "Package Geometry/Pastemask Bottom")
		(5 "F.SilkS" user "Ref Des/Silkscreen Top")
		(7 "B.SilkS" user "Ref Des/Silkscreen Bottom")
		(1 "F.Mask" user "Board Geometry/Soldermask Top")
		(3 "B.Mask" user "Board Geometry/Soldermask Bottom")
		(17 "Dwgs.User" user "User.Drawings")
		(19 "Cmts.User" user "User.Comments")
		(21 "Eco1.User" user "User.Eco1")
		(23 "Eco2.User" user "User.Eco2")
		(25 "Edge.Cuts" user "Board Geometry/Outline")
		(27 "Margin" user)
		(31 "F.CrtYd" user "Package Geometry/Place Bound Top")
		(29 "B.CrtYd" user "Package Geometry/Place Bound Bottom")
		(35 "F.Fab" user "Ref Des/Assembly Top")
		(33 "B.Fab" user "Ref Des/Assembly Bottom")
	)
	(footprint ""
		(layer "B.Cu")
		(at 444.548006 -41.648126 180)
		(property "Reference" "R25W18"
			(at 0 0 0)
			(layer "B.SilkS")
			(hide yes)
			(effects
				(font
					(size 1.27 1.27)
				)
				(justify mirror)
			)
		)
		(property "Value" "*"
			(at -0.064008 -4.108196 180)
			(unlocked yes)
			(layer "B.Fab")
			(hide yes)
			(effects
				(font
					(size 1.27 1.016)
					(thickness 0.1524)
				)
				(justify mirror)
			)
		)
		(property "Device Type" "120R2F-GP_RCL_GP-120R2F-GP,64.A"
			(at -0.064008 -5.632196 180)
			(unlocked yes)
			(layer "B.Fab")
			(hide yes)
			(effects
				(font
					(size 1.27 1.016)
					(thickness 0.1524)
				)
				(justify mirror)
			)
		)
		(duplicate_pad_numbers_are_jumpers no)
		(fp_line
			(start 0.508 -0.9398)
			(end 0.508 0.9398)
			(stroke
				(width 0.1524)
				(type default)
			)
			(layer "B.SilkS")
		)
		(fp_line
			(start -0.508 -0.9398)
			(end 0.508 -0.9398)
			(stroke
				(width 0.1524)
				(type default)
			)
			(layer "B.SilkS")
		)
		(fp_rect
			(start 0.508 0.9398)
			(end -0.508 -0.9398)
			(stroke
				(width 0)
				(type default)
			)
			(fill no)
			(layer "B.CrtYd")
		)
		(fp_rect
			(start 0.508 0.9398)
			(end -0.508 -0.9398)
			(stroke
				(width 0)
				(type default)
			)
			(fill no)
			(layer "B.Fab")
		)
		(pad "1" smd custom
			(at 0 -0.4445)
			(size 0.1397 0.1397)
			(layers "B.Cu" "B.Mask" "B.Paste")
			(net "GND")
			(options
				(clearance outline)
				(anchor circle)
			)
			(primitives
				(gr_poly
					(pts
						(arc
							(start -0.1778 0.2794)
							(mid -0.249642 0.249642)
							(end -0.2794 0.1778)
						)
						(arc
							(start -0.2794 -0.1778)
							(mid -0.249642 -0.249642)
							(end -0.1778 -0.2794)
						)
						(arc
							(start 0.1778 -0.2794)
							(mid 0.249642 -0.249642)
							(end 0.2794 -0.1778)
						)
						(arc
							(start 0.2794 0.1778)
							(mid 0.249642 0.249642)
							(end 0.1778 0.2794)
						)
					)
					(width 0)
					(fill yes)
				)
			)
		)
		(pad "2" smd custom
			(at 0 0.4445)
			(size 0.1397 0.1397)
			(layers "B.Cu" "B.Mask" "B.Paste")
			(net "BMC_M_A6")
			(options
				(clearance outline)
				(anchor circle)
			)
			(primitives
				(gr_poly
					(pts
						(arc
							(start -0.1778 0.2794)
							(mid -0.249642 0.249642)
							(end -0.2794 0.1778)
						)
						(arc
							(start -0.2794 -0.1778)
							(mid -0.249642 -0.249642)
							(end -0.1778 -0.2794)
						)
						(arc
							(start 0.1778 -0.2794)
							(mid 0.249642 -0.249642)
							(end 0.2794 -0.1778)
						)
						(arc
							(start 0.2794 0.1778)
							(mid 0.249642 0.249642)
							(end 0.1778 0.2794)
						)
					)
					(width 0)
					(fill yes)
				)
			)
		)
	)
	(footprint ""
		(layer "B.Cu")
		(at 197.226428 -95.171006 90)
		(property "Reference" "R6N3"
			(at 0 0 90)
			(layer "B.SilkS")
			(hide yes)
			(effects
				(font
					(size 1.27 1.27)
				)
				(justify mirror)
			)
		)
		(property "Value" ""
			(at 0 0 90)
			(layer "B.Fab")
			(effects
				(font
					(size 1.27 1.27)
				)
				(justify mirror)
			)
		)
		(duplicate_pad_numbers_are_jumpers no)
		(fp_rect
			(start 0.2794 -0.1016)
			(end -0.2794 0.9906)
			(stroke
				(width 0)
				(type default)
			)
			(fill no)
			(layer "B.CrtYd")
		)
		(fp_line
			(start 0.2794 -0.1016)
			(end 0.2794 0.9906)
			(stroke
				(width 0.1)
				(type default)
			)
			(layer "B.Fab")
		)
		(fp_line
			(start -0.2794 -0.1016)
			(end 0.2794 -0.1016)
			(stroke
				(width 0.1)
				(type default)
			)
			(layer "B.Fab")
		)
		(fp_line
			(start 0.2794 0.9906)
			(end -0.2794 0.9906)
			(stroke
				(width 0.1)
				(type default)
			)
			(layer "B.Fab")
		)
		(fp_line
			(start -0.2794 0.9906)
			(end -0.2794 -0.1016)
			(stroke
				(width 0.1)
				(type default)
			)
			(layer "B.Fab")
		)
		(pad "1" smd rect
			(at 0 0 270)
			(size 0.508 0.508)
			(layers "B.Cu" "B.Mask" "B.Paste")
			(net "VR_PVSA_CPU0_VCIN")
		)
		(pad "2" smd rect
			(at 0 0.889 270)
			(size 0.508 0.508)
			(layers "B.Cu" "B.Mask" "B.Paste")
			(net "P5V_STBY")
		)
		(zone
			(layer "B.Cu")
			(hatch none 0.5)
			(connect_pads
				(clearance 0)
			)
			(min_thickness 0.25)
			(keepout
				(tracks not_allowed)
				(vias allowed)
				(pads allowed)
				(copperpour not_allowed)
				(footprints allowed)
			)
			(placement
				(enabled no)
				(sheetname "")
			)
			(fill
				(thermal_gap 0.5)
				(thermal_bridge_width 0.5)
				(island_removal_mode 0)
			)
			(polygon
				(pts
					(xy 197.480428 -95.425006) (xy 197.480428 -94.917006) (xy 197.861428 -94.917006) (xy 197.861428 -95.425006)
				)
			)
		)
		(zone
			(layer "B.Cu")
			(hatch none 0.5)
			(connect_pads
				(clearance 0)
			)
			(min_thickness 0.25)
			(keepout
				(tracks allowed)
				(vias not_allowed)
				(pads allowed)
				(copperpour not_allowed)
				(footprints allowed)
			)
			(placement
				(enabled no)
				(sheetname "")
			)
			(fill
				(thermal_gap 0.5)
				(thermal_bridge_width 0.5)
				(island_removal_mode 0)
			)
			(polygon
				(pts
					(xy 197.480428 -95.425006) (xy 197.480428 -94.917006) (xy 197.861428 -94.917006) (xy 197.861428 -95.425006)
				)
			)
		)
	)
	(footprint ""
		(layer "B.Cu")
		(at 40.936418 -103.482648 90)
		(property "Reference" "R1C12"
			(at 0.8382 -0.67818 90)
			(unlocked yes)
			(layer "B.SilkS")
			(effects
				(font
					(size 0.4064 0.254)
					(thickness 0.1524)
				)
				(justify left mirror)
			)
		)
		(property "Value" ""
			(at 0 0 90)
			(layer "B.Fab")
			(effects
				(font
					(size 1.27 1.27)
				)
				(justify mirror)
			)
		)
		(duplicate_pad_numbers_are_jumpers no)
		(fp_poly
			(pts
				(xy 0.2794 -0.1016) (xy -0.2794 -0.1016) (xy -0.2794 0.9906) (xy 0.2794 0.9906)
			)
			(stroke
				(width 0)
				(type default)
			)
			(fill no)
			(layer "B.CrtYd")
		)
		(fp_line
			(start 0.2794 -0.1016)
			(end 0.2794 0.9906)
			(stroke
				(width 0.1)
				(type default)
			)
			(layer "B.Fab")
		)
		(fp_line
			(start -0.2794 -0.1016)
			(end 0.2794 -0.1016)
			(stroke
				(width 0.1)
				(type default)
			)
			(layer "B.Fab")
		)
		(fp_line
			(start 0.2794 0.9906)
			(end -0.2794 0.9906)
			(stroke
				(width 0.1)
				(type default)
			)
			(layer "B.Fab")
		)
		(fp_line
			(start -0.2794 0.9906)
			(end -0.2794 -0.1016)
			(stroke
				(width 0.1)
				(type default)
			)
			(layer "B.Fab")
		)
		(pad "1" smd rect
			(at 0 0 270)
			(size 0.508 0.508)
			(layers "B.Cu" "B.Mask" "B.Paste")
			(net "VSENSE_PVSA_CPU1_P")
		)
		(pad "2" smd rect
			(at 0 0.889 270)
			(size 0.508 0.508)
			(layers "B.Cu" "B.Mask" "B.Paste")
			(net "PVSA_CPU1")
		)
		(zone
			(layer "B.Cu")
			(hatch none 0.5)
			(connect_pads
				(clearance 0)
			)
			(min_thickness 0.25)
			(keepout
				(tracks allowed)
				(vias not_allowed)
				(pads allowed)
				(copperpour not_allowed)
				(footprints allowed)
			)
			(placement
				(enabled no)
				(sheetname "")
			)
			(fill
				(thermal_gap 0.5)
				(thermal_bridge_width 0.5)
				(island_removal_mode 0)
			)
			(polygon
				(pts
					(xy 41.190418 -103.736648) (xy 41.190418 -103.228648) (xy 41.571418 -103.228648) (xy 41.571418 -103.736648)
				)
			)
		)
		(zone
			(layer "B.Cu")
			(hatch none 0.5)
			(connect_pads
				(clearance 0)
			)
			(min_thickness 0.25)
			(keepout
				(tracks not_allowed)
				(vias allowed)
				(pads allowed)
				(copperpour not_allowed)
				(footprints allowed)
			)
			(placement
				(enabled no)
				(sheetname "")
			)
			(fill
				(thermal_gap 0.5)
				(thermal_bridge_width 0.5)
				(island_removal_mode 0)
			)
			(polygon
				(pts
					(xy 41.571418 -103.736648) (xy 41.571418 -103.228648) (xy 41.190418 -103.228648) (xy 41.190418 -103.736648)
				)
			)
		)
	)
)
